(kicad_pcb
	(version 20260206)
	(generator "pcbnew")
	(generator_version "10.0")
	(general
		(thickness 1.6)
		(legacy_teardrops no)
	)
	(paper "A4")
	(title_block
		(title "Wiwynn_Tioga_Pass_MB.brd")
		(comment 1 "Tioga Pass / footprints 74-79 of 4770")
	)
	(layers
		(0 "F.Cu" signal "TOP")
		(4 "In1.Cu" signal "L2GND")
		(6 "In2.Cu" signal "L3")
		(8 "In3.Cu" signal "L4GND")
		(10 "In4.Cu" signal "L5")
		(12 "In5.Cu" signal "L6GND")
		(14 "In6.Cu" signal "L7VCC")
		(16 "In7.Cu" signal "L8VCC")
		(18 "In8.Cu" signal "L9GND")
		(20 "In9.Cu" signal "L10")
		(22 "In10.Cu" signal "L11GND")
		(24 "In11.Cu" signal "L12")
		(26 "In12.Cu" signal "L13GND")
		(2 "B.Cu" signal "BOTTOM")
		(9 "F.Adhes" user "F.Adhesive")
		(11 "B.Adhes" user "B.Adhesive")
		(13 "F.Paste" user "Package Geometry/Pastemask Top")
		(15 "B.Paste" user "Package Geometry/Pastemask Bottom")
		(5 "F.SilkS" user "Ref Des/Silkscreen Top")
		(7 "B.SilkS" user "Ref Des/Silkscreen Bottom")
		(1 "F.Mask" user "Board Geometry/Soldermask Top")
		(3 "B.Mask" user "Board Geometry/Soldermask Bottom")
		(17 "Dwgs.User" user "User.Drawings")
		(19 "Cmts.User" user "User.Comments")
		(21 "Eco1.User" user "User.Eco1")
		(23 "Eco2.User" user "User.Eco2")
		(25 "Edge.Cuts" user "Board Geometry/Outline")
		(27 "Margin" user)
		(31 "F.CrtYd" user "Package Geometry/Place Bound Top")
		(29 "B.CrtYd" user "Package Geometry/Place Bound Bottom")
		(35 "F.Fab" user "Ref Des/Assembly Top")
		(33 "B.Fab" user "Ref Des/Assembly Bottom")
	)
	(footprint ""
		(layer "F.Cu")
		(at 204.5462 -85.4456 -90)
		(property "Reference" "CT35"
			(at -0.8382 -0.67818 270)
			(unlocked yes)
			(layer "F.SilkS")
			(effects
				(font
					(size 0.4064 0.254)
					(thickness 0.1524)
				)
				(justify left)
			)
		)
		(property "Value" ""
			(at 0 0 270)
			(layer "F.Fab")
			(effects
				(font
					(size 1.27 1.27)
				)
			)
		)
		(duplicate_pad_numbers_are_jumpers no)
		(fp_poly
			(pts
				(xy 0.3048 -0.1016) (xy 0.3048 0.9906) (xy -0.3048 0.9906) (xy -0.3048 -0.1016)
			)
			(stroke
				(width 0)
				(type default)
			)
			(fill no)
			(layer "F.CrtYd")
		)
		(fp_line
			(start -0.3048 0.9906)
			(end 0.3048 0.9906)
			(stroke
				(width 0.1)
				(type default)
			)
			(layer "F.Fab")
		)
		(fp_line
			(start 0.3048 0.9906)
			(end 0.3048 -0.1016)
			(stroke
				(width 0.1)
				(type default)
			)
			(layer "F.Fab")
		)
		(fp_line
			(start -0.3048 -0.1016)
			(end -0.3048 0.9906)
			(stroke
				(width 0.1)
				(type default)
			)
			(layer "F.Fab")
		)
		(fp_line
			(start 0.3048 -0.1016)
			(end -0.3048 -0.1016)
			(stroke
				(width 0.1)
				(type default)
			)
			(layer "F.Fab")
		)
		(pad "1" smd rect
			(at 0 0 270)
			(size 0.508 0.508)
			(layers "F.Cu" "F.Mask" "F.Paste")
			(net "VR_PVCCIN_CPU0_PHASE5")
		)
		(pad "2" smd rect
			(at 0 0.889 270)
			(size 0.508 0.508)
			(layers "F.Cu" "F.Mask" "F.Paste")
			(net "VR_PVCCIN_CPU0_PHASE5_RC")
		)
		(zone
			(layer "F.Cu")
			(hatch none 0.5)
			(connect_pads
				(clearance 0)
			)
			(min_thickness 0.25)
			(keepout
				(tracks not_allowed)
				(vias allowed)
				(pads allowed)
				(copperpour not_allowed)
				(footprints allowed)
			)
			(placement
				(enabled no)
				(sheetname "")
			)
			(fill
				(thermal_gap 0.5)
				(thermal_bridge_width 0.5)
				(island_removal_mode 0)
			)
			(polygon
				(pts
					(xy 203.9112 -85.6996) (xy 203.9112 -85.1916) (xy 204.2922 -85.1916) (xy 204.2922 -85.6996)
				)
			)
		)
		(zone
			(layer "F.Cu")
			(hatch none 0.5)
			(connect_pads
				(clearance 0)
			)
			(min_thickness 0.25)
			(keepout
				(tracks allowed)
				(vias not_allowed)
				(pads allowed)
				(copperpour not_allowed)
				(footprints allowed)
			)
			(placement
				(enabled no)
				(sheetname "")
			)
			(fill
				(thermal_gap 0.5)
				(thermal_bridge_width 0.5)
				(island_removal_mode 0)
			)
			(polygon
				(pts
					(xy 204.2922 -85.6996) (xy 204.2922 -85.1916) (xy 203.9112 -85.1916) (xy 203.9112 -85.6996)
				)
			)
		)
	)
	(footprint ""
		(layer "F.Cu")
		(at 403.86 -123.7742 90)
		(property "Reference" "R8B32"
			(at 0 0 90)
			(layer "F.SilkS")
			(hide yes)
			(effects
				(font
					(size 1.27 1.27)
				)
			)
		)
		(property "Value" ""
			(at 0 0 90)
			(layer "F.Fab")
			(effects
				(font
					(size 1.27 1.27)
				)
			)
		)
		(duplicate_pad_numbers_are_jumpers no)
		(fp_poly
			(pts
				(xy -0.2794 -0.1016) (xy 0.2794 -0.1016) (xy 0.2794 0.9906) (xy -0.2794 0.9906)
			)
			(stroke
				(width 0)
				(type default)
			)
			(fill no)
			(layer "F.CrtYd")
		)
		(fp_line
			(start 0.2794 -0.1016)
			(end -0.2794 -0.1016)
			(stroke
				(width 0.1)
				(type default)
			)
			(layer "F.Fab")
		)
		(fp_line
			(start -0.2794 -0.1016)
			(end -0.2794 0.9906)
			(stroke
				(width 0.1)
				(type default)
			)
			(layer "F.Fab")
		)
		(fp_line
			(start 0.2794 0.9906)
			(end 0.2794 -0.1016)
			(stroke
				(width 0.1)
				(type default)
			)
			(layer "F.Fab")
		)
		(fp_line
			(start -0.2794 0.9906)
			(end 0.2794 0.9906)
			(stroke
				(width 0.1)
				(type default)
			)
			(layer "F.Fab")
		)
		(pad "1" smd rect
			(at 0 0 90)
			(size 0.508 0.508)
			(layers "F.Cu" "F.Mask" "F.Paste")
			(net "A_USB2_VBUS")
		)
		(pad "2" smd rect
			(at 0 0.889 90)
			(size 0.508 0.508)
			(layers "F.Cu" "F.Mask" "F.Paste")
			(net "GND")
		)
		(zone
			(layer "F.Cu")
			(hatch none 0.5)
			(connect_pads
				(clearance 0)
			)
			(min_thickness 0.25)
			(keepout
				(tracks allowed)
				(vias not_allowed)
				(pads allowed)
				(copperpour not_allowed)
				(footprints allowed)
			)
			(placement
				(enabled no)
				(sheetname "")
			)
			(fill
				(thermal_gap 0.5)
				(thermal_bridge_width 0.5)
				(island_removal_mode 0)
			)
			(polygon
				(pts
					(xy 404.114 -123.5202) (xy 404.114 -124.0282) (xy 404.495 -124.0282) (xy 404.495 -123.5202)
				)
			)
		)
		(zone
			(layer "F.Cu")
			(hatch none 0.5)
			(connect_pads
				(clearance 0)
			)
			(min_thickness 0.25)
			(keepout
				(tracks not_allowed)
				(vias allowed)
				(pads allowed)
				(copperpour not_allowed)
				(footprints allowed)
			)
			(placement
				(enabled no)
				(sheetname "")
			)
			(fill
				(thermal_gap 0.5)
				(thermal_bridge_width 0.5)
				(island_removal_mode 0)
			)
			(polygon
				(pts
					(xy 404.495 -123.5202) (xy 404.495 -124.0282) (xy 404.114 -124.0282) (xy 404.114 -123.5202)
				)
			)
		)
	)
	(footprint ""
		(layer "F.Cu")
		(at 384.048 -64.2874 180)
		(property "Reference" "FB7E1"
			(at -1.48717 0.635 270)
			(unlocked yes)
			(layer "F.SilkS")
			(effects
				(font
					(size 0.7874 0.5842)
					(thickness 0.1524)
				)
			)
		)
		(property "Value" ""
			(at 0 0 180)
			(layer "F.Fab")
			(effects
				(font
					(size 1.27 1.27)
				)
			)
		)
		(duplicate_pad_numbers_are_jumpers no)
		(fp_poly
			(pts
				(xy -0.7239 -0.26035) (xy 0.7239 -0.26035) (xy 0.7239 2.03835) (xy -0.7239 2.03835)
			)
			(stroke
				(width 0)
				(type default)
			)
			(fill no)
			(layer "F.CrtYd")
		)
		(fp_line
			(start 0.7239 2.03835)
			(end -0.7239 2.03835)
			(stroke
				(width 0.1)
				(type default)
			)
			(layer "F.Fab")
		)
		(fp_line
			(start 0.7239 -0.26035)
			(end 0.7239 2.03835)
			(stroke
				(width 0.1)
				(type default)
			)
			(layer "F.Fab")
		)
		(fp_line
			(start -0.7239 2.03835)
			(end -0.7239 -0.26035)
			(stroke
				(width 0.1)
				(type default)
			)
			(layer "F.Fab")
		)
		(fp_line
			(start -0.7239 -0.26035)
			(end 0.7239 -0.26035)
			(stroke
				(width 0.1)
				(type default)
			)
			(layer "F.Fab")
		)
		(pad "1" smd rect
			(at 0 0 180)
			(size 1.27 1.016)
			(layers "F.Cu" "F.Mask" "F.Paste")
			(net "P12V_STBY")
		)
		(pad "2" smd rect
			(at 0 1.778 180)
			(size 1.27 1.016)
			(layers "F.Cu" "F.Mask" "F.Paste")
			(net "VR_FET_SW_P5V_STBY_PVIN")
		)
		(zone
			(layer "F.Cu")
			(hatch none 0.5)
			(connect_pads
				(clearance 0)
			)
			(min_thickness 0.25)
			(keepout
				(tracks not_allowed)
				(vias allowed)
				(pads allowed)
				(copperpour not_allowed)
				(footprints allowed)
			)
			(placement
				(enabled no)
				(sheetname "")
			)
			(fill
				(thermal_gap 0.5)
				(thermal_bridge_width 0.5)
				(island_removal_mode 0)
			)
			(polygon
				(pts
					(xy 383.413 -64.7954) (xy 383.413 -65.5574) (xy 383.5019 -65.5574) (xy 384.683 -65.5574) (xy 384.683 -64.7954)
				)
			)
		)
	)
	(footprint ""
		(layer "F.Cu")
		(at 411.0355 -112.395 -90)
		(property "Reference" "R8C2"
			(at 0 0 270)
			(layer "F.SilkS")
			(hide yes)
			(effects
				(font
					(size 1.27 1.27)
				)
			)
		)
		(property "Value" ""
			(at 0 0 270)
			(layer "F.Fab")
			(effects
				(font
					(size 1.27 1.27)
				)
			)
		)
		(duplicate_pad_numbers_are_jumpers no)
		(fp_poly
			(pts
				(xy -0.2794 -0.1016) (xy 0.2794 -0.1016) (xy 0.2794 0.9906) (xy -0.2794 0.9906)
			)
			(stroke
				(width 0)
				(type default)
			)
			(fill no)
			(layer "F.CrtYd")
		)
		(fp_line
			(start -0.2794 0.9906)
			(end 0.2794 0.9906)
			(stroke
				(width 0.1)
				(type default)
			)
			(layer "F.Fab")
		)
		(fp_line
			(start 0.2794 0.9906)
			(end 0.2794 -0.1016)
			(stroke
				(width 0.1)
				(type default)
			)
			(layer "F.Fab")
		)
		(fp_line
			(start -0.2794 -0.1016)
			(end -0.2794 0.9906)
			(stroke
				(width 0.1)
				(type default)
			)
			(layer "F.Fab")
		)
		(fp_line
			(start 0.2794 -0.1016)
			(end -0.2794 -0.1016)
			(stroke
				(width 0.1)
				(type default)
			)
			(layer "F.Fab")
		)
		(pad "1" smd rect
			(at 0 0 270)
			(size 0.508 0.508)
			(layers "F.Cu" "F.Mask" "F.Paste")
			(net "P3V3_STBY")
		)
		(pad "2" smd rect
			(at 0 0.889 270)
			(size 0.508 0.508)
			(layers "F.Cu" "F.Mask" "F.Paste")
			(net "IRQ_BMC_PCH_SCI_LPC_N")
		)
		(zone
			(layer "F.Cu")
			(hatch none 0.5)
			(connect_pads
				(clearance 0)
			)
			(min_thickness 0.25)
			(keepout
				(tracks not_allowed)
				(vias allowed)
				(pads allowed)
				(copperpour not_allowed)
				(footprints allowed)
			)
			(placement
				(enabled no)
				(sheetname "")
			)
			(fill
				(thermal_gap 0.5)
				(thermal_bridge_width 0.5)
				(island_removal_mode 0)
			)
			(polygon
				(pts
					(xy 410.4005 -112.649) (xy 410.4005 -112.141) (xy 410.7815 -112.141) (xy 410.7815 -112.649)
				)
			)
		)
		(zone
			(layer "F.Cu")
			(hatch none 0.5)
			(connect_pads
				(clearance 0)
			)
			(min_thickness 0.25)
			(keepout
				(tracks allowed)
				(vias not_allowed)
				(pads allowed)
				(copperpour not_allowed)
				(footprints allowed)
			)
			(placement
				(enabled no)
				(sheetname "")
			)
			(fill
				(thermal_gap 0.5)
				(thermal_bridge_width 0.5)
				(island_removal_mode 0)
			)
			(polygon
				(pts
					(xy 410.7815 -112.649) (xy 410.7815 -112.141) (xy 410.4005 -112.141) (xy 410.4005 -112.649)
				)
			)
		)
	)
	(footprint ""
		(layer "F.Cu")
		(at 13.8938 -27.686 90)
		(property "Reference" "C1F14"
			(at 0 0 90)
			(layer "F.SilkS")
			(hide yes)
			(effects
				(font
					(size 1.27 1.27)
				)
			)
		)
		(property "Value" ""
			(at 0 0 90)
			(layer "F.Fab")
			(effects
				(font
					(size 1.27 1.27)
				)
			)
		)
		(duplicate_pad_numbers_are_jumpers no)
		(fp_rect
			(start -0.3048 -0.1016)
			(end 0.3048 0.9906)
			(stroke
				(width 0)
				(type default)
			)
			(fill no)
			(layer "F.CrtYd")
		)
		(fp_line
			(start 0.3048 -0.1016)
			(end -0.3048 -0.1016)
			(stroke
				(width 0.1)
				(type default)
			)
			(layer "F.Fab")
		)
		(fp_line
			(start -0.3048 -0.1016)
			(end -0.3048 0.9906)
			(stroke
				(width 0.1)
				(type default)
			)
			(layer "F.Fab")
		)
		(fp_line
			(start 0.3048 0.9906)
			(end 0.3048 -0.1016)
			(stroke
				(width 0.1)
				(type default)
			)
			(layer "F.Fab")
		)
		(fp_line
			(start -0.3048 0.9906)
			(end 0.3048 0.9906)
			(stroke
				(width 0.1)
				(type default)
			)
			(layer "F.Fab")
		)
		(pad "1" smd rect
			(at 0 0 90)
			(size 0.508 0.508)
			(layers "F.Cu" "F.Mask" "F.Paste")
			(net "P3E_CPU1_PE3_MP_C_TXP<2>")
		)
		(pad "2" smd rect
			(at 0 0.889 90)
			(size 0.508 0.508)
			(layers "F.Cu" "F.Mask" "F.Paste")
			(net "P3E_CPU1_PE3_MP_TXP<2>")
		)
		(zone
			(layer "F.Cu")
			(hatch none 0.5)
			(connect_pads
				(clearance 0)
			)
			(min_thickness 0.25)
			(keepout
				(tracks allowed)
				(vias not_allowed)
				(pads allowed)
				(copperpour not_allowed)
				(footprints allowed)
			)
			(placement
				(enabled no)
				(sheetname "")
			)
			(fill
				(thermal_gap 0.5)
				(thermal_bridge_width 0.5)
				(island_removal_mode 0)
			)
			(polygon
				(pts
					(xy 14.1478 -27.432) (xy 14.5288 -27.432) (xy 14.5288 -27.94) (xy 14.1478 -27.94)
				)
			)
		)
		(zone
			(layer "F.Cu")
			(hatch none 0.5)
			(connect_pads
				(clearance 0)
			)
			(min_thickness 0.25)
			(keepout
				(tracks not_allowed)
				(vias allowed)
				(pads allowed)
				(copperpour not_allowed)
				(footprints allowed)
			)
			(placement
				(enabled no)
				(sheetname "")
			)
			(fill
				(thermal_gap 0.5)
				(thermal_bridge_width 0.5)
				(island_removal_mode 0)
			)
			(polygon
				(pts
					(xy 14.1478 -27.432) (xy 14.5288 -27.432) (xy 14.5288 -27.94) (xy 14.1478 -27.94)
				)
			)
		)
	)
	(footprint ""
		(layer "F.Cu")
		(at 450.461634 -141.30909 180)
		(property "Reference" "U25W10"
			(at 2.159 -1.57988 180)
			(unlocked yes)
			(layer "F.SilkS")
			(effects
				(font
					(size 0.4064 0.254)
					(thickness 0.1524)
				)
				(justify left)
			)
		)
		(property "Value" ""
			(at 0 0 180)
			(layer "F.Fab")
			(effects
				(font
					(size 1.27 1.27)
				)
			)
		)
		(duplicate_pad_numbers_are_jumpers no)
		(fp_line
			(start 4.4323 4.52628)
			(end 1.5367 4.52628)
			(stroke
				(width 0.1524)
				(type default)
			)
			(layer "F.SilkS")
		)
		(fp_line
			(start 4.4323 -0.64008)
			(end 4.4323 4.52628)
			(stroke
				(width 0.1524)
				(type default)
			)
			(layer "F.SilkS")
		)
		(fp_line
			(start 3.302 0.49022)
			(end 3.302 -0.64008)
			(stroke
				(width 0.1524)
				(type default)
			)
			(layer "F.SilkS")
		)
		(fp_line
			(start 2.667 0.49022)
			(end 3.302 0.49022)
			(stroke
				(width 0.1524)
				(type default)
			)
			(layer "F.SilkS")
		)
		(fp_line
			(start 2.667 -0.64008)
			(end 2.667 0.49022)
			(stroke
				(width 0.1524)
				(type default)
			)
			(layer "F.SilkS")
		)
		(fp_line
			(start 1.5367 4.52628)
			(end 1.5367 -0.64008)
			(stroke
				(width 0.1524)
				(type default)
			)
			(layer "F.SilkS")
		)
		(fp_line
			(start 1.5367 -0.64008)
			(end 4.4323 -0.64008)
			(stroke
				(width 0.1524)
				(type default)
			)
			(layer "F.SilkS")
		)
		(fp_circle
			(center -1.612138 -0.684784)
			(end -1.739138 -0.684784)
			(stroke
				(width 0.254)
				(type default)
			)
			(fill no)
			(layer "F.SilkS")
		)
		(fp_poly
			(pts
				(xy 0.7366 4.54152) (xy 0.7366 -0.64008) (xy 4.7244 -0.64008) (xy 5.2324 -0.64008) (xy 5.2324 4.54152)
				(xy 4.7244 4.54152)
			)
			(stroke
				(width 0)
				(type default)
			)
			(fill no)
			(layer "F.CrtYd")
		)
		(fp_line
			(start 5.2324 4.54152)
			(end 0.7366 4.54152)
			(stroke
				(width 0.1)
				(type default)
			)
			(layer "F.Fab")
		)
		(fp_line
			(start 5.2324 -0.64008)
			(end 5.2324 4.54152)
			(stroke
				(width 0.1)
				(type default)
			)
			(layer "F.Fab")
		)
		(fp_line
			(start 3.302 0.49022)
			(end 3.302 -0.64008)
			(stroke
				(width 0.1)
				(type default)
			)
			(layer "F.Fab")
		)
		(fp_line
			(start 2.667 0.49022)
			(end 3.302 0.49022)
			(stroke
				(width 0.1)
				(type default)
			)
			(layer "F.Fab")
		)
		(fp_line
			(start 2.667 -0.64008)
			(end 2.667 0.49022)
			(stroke
				(width 0.1)
				(type default)
			)
			(layer "F.Fab")
		)
		(fp_line
			(start 0.7366 4.54152)
			(end 0.7366 -0.64008)
			(stroke
				(width 0.1)
				(type default)
			)
			(layer "F.Fab")
		)
		(fp_line
			(start 0.7366 -0.64008)
			(end 5.2324 -0.64008)
			(stroke
				(width 0.1)
				(type default)
			)
			(layer "F.Fab")
		)
		(fp_circle
			(center -1.612138 -0.684784)
			(end -1.739138 -0.684784)
			(stroke
				(width 0.254)
				(type default)
			)
			(fill no)
			(layer "F.Fab")
		)
		(pad "1" smd rect
			(at 0 0 180)
			(size 2.159 0.381)
			(layers "F.Cu" "F.Mask" "F.Paste")
			(net "PU_GTL2014_3_DIR")
		)
		(pad "2" smd rect
			(at 0 0.65024 180)
			(size 2.159 0.381)
			(layers "F.Cu" "F.Mask" "F.Paste")
			(net "XDP_PREQ_N")
		)
		(pad "3" smd rect
			(at 0 1.30048 180)
			(size 2.159 0.381)
			(layers "F.Cu" "F.Mask" "F.Paste")
			(net "XDP_CPU_PWR_DEBUG_N")
		)
		(pad "4" smd rect
			(at 0 1.95072 180)
			(size 2.159 0.381)
			(layers "F.Cu" "F.Mask" "F.Paste")
			(net "PD_GTL2014_3_VREF")
		)
		(pad "5" smd rect
			(at 0 2.60096 180)
			(size 2.159 0.381)
			(layers "F.Cu" "F.Mask" "F.Paste")
			(net "XDP_TDI_R")
		)
		(pad "6" smd rect
			(at 0 3.2512 180)
			(size 2.159 0.381)
			(layers "F.Cu" "F.Mask" "F.Paste")
			(net "XDP_TMS_R")
		)
		(pad "7" smd rect
			(at 0 3.90144 180)
			(size 2.159 0.381)
			(layers "F.Cu" "F.Mask" "F.Paste")
			(net "GND")
		)
		(pad "8" smd rect
			(at 5.969 3.90144 180)
			(size 2.159 0.381)
			(layers "F.Cu" "F.Mask" "F.Paste")
			(net "GND")
		)
		(pad "9" smd rect
			(at 5.969 3.2512 180)
			(size 2.159 0.381)
			(layers "F.Cu" "F.Mask" "F.Paste")
			(net "JTAG_BMC_BUF_TMS")
		)
		(pad "10" smd rect
			(at 5.969 2.60096 180)
			(size 2.159 0.381)
			(layers "F.Cu" "F.Mask" "F.Paste")
			(net "JTAG_BMC_BUF_TDI")
		)
		(pad "11" smd rect
			(at 5.969 1.95072 180)
			(size 2.159 0.381)
			(layers "F.Cu" "F.Mask" "F.Paste")
			(net "GND")
		)
		(pad "12" smd rect
			(at 5.969 1.30048 180)
			(size 2.159 0.381)
			(layers "F.Cu" "F.Mask" "F.Paste")
			(net "BMC_PWR_DEBUG_BUF_N")
		)
		(pad "13" smd rect
			(at 5.969 0.65024 180)
			(size 2.159 0.381)
			(layers "F.Cu" "F.Mask" "F.Paste")
			(net "BMC_PREQ_BUF_N")
		)
		(pad "14" smd rect
			(at 5.969 0 180)
			(size 2.159 0.381)
			(layers "F.Cu" "F.Mask" "F.Paste")
			(net "P3V3_STBY")
		)
	)
)
